(kicad_pcb
	(version 20260206)
	(generator "pcbnew")
	(generator_version "10.0")
	(general
		(thickness 1.6)
		(legacy_teardrops no)
	)
	(paper "A4")
	(title_block
		(title "Bryce Canyon_SCC_16316-1_OCP.brd")
		(comment 1 "Bryce Canyon / footprints 592-599 of 1561")
	)
	(layers
		(0 "F.Cu" signal "TOP")
		(4 "In1.Cu" signal "L2GND")
		(6 "In2.Cu" signal "L3")
		(8 "In3.Cu" signal "L4VCC")
		(10 "In4.Cu" signal "L5VCC")
		(12 "In5.Cu" signal "L6")
		(14 "In6.Cu" signal "L7GND")
		(2 "B.Cu" signal "BOTTOM")
		(9 "F.Adhes" user "F.Adhesive")
		(11 "B.Adhes" user "B.Adhesive")
		(13 "F.Paste" user "Package Geometry/Pastemask Top")
		(15 "B.Paste" user "Package Geometry/Pastemask Bottom")
		(5 "F.SilkS" user "Ref Des/Silkscreen Top")
		(7 "B.SilkS" user "Ref Des/Silkscreen Bottom")
		(1 "F.Mask" user "Board Geometry/Soldermask Top")
		(3 "B.Mask" user "Board Geometry/Soldermask Bottom")
		(17 "Dwgs.User" user "User.Drawings")
		(19 "Cmts.User" user "User.Comments")
		(21 "Eco1.User" user "User.Eco1")
		(23 "Eco2.User" user "User.Eco2")
		(25 "Edge.Cuts" user "Board Geometry/Outline")
		(27 "Margin" user)
		(31 "F.CrtYd" user "Package Geometry/Place Bound Top")
		(29 "B.CrtYd" user "Package Geometry/Place Bound Bottom")
		(35 "F.Fab" user "Ref Des/Assembly Top")
		(33 "B.Fab" user "Ref Des/Assembly Bottom")
	)
	(footprint ""
		(layer "F.Cu")
		(at 20.6502 -46.99)
		(property "Reference" "C649"
			(at 0 0 0)
			(layer "F.SilkS")
			(hide yes)
			(effects
				(font
					(size 1.27 1.27)
				)
			)
		)
		(property "Value" "SC1U16V3KX-5GP"
			(at 0 -2.8194 0)
			(unlocked yes)
			(layer "F.Fab")
			(hide yes)
			(effects
				(font
					(size 1.016 1.016)
					(thickness 0.1524)
				)
			)
		)
		(property "Device Type" "C603H36"
			(at 0 -4.3434 0)
			(unlocked yes)
			(layer "F.Fab")
			(hide yes)
			(effects
				(font
					(size 1.016 1.016)
					(thickness 0.1524)
				)
			)
		)
		(duplicate_pad_numbers_are_jumpers no)
		(fp_line
			(start 0.508 0)
			(end -0.508 0)
			(stroke
				(width 0.2032)
				(type default)
			)
			(layer "F.SilkS")
		)
		(fp_rect
			(start -0.5842 1.3335)
			(end 0.5842 -1.3335)
			(stroke
				(width 0)
				(type default)
			)
			(fill no)
			(layer "F.CrtYd")
		)
		(fp_rect
			(start -0.5842 1.3335)
			(end 0.5842 -1.3335)
			(stroke
				(width 0)
				(type default)
			)
			(fill no)
			(layer "F.Fab")
		)
		(pad "1" smd custom
			(at 0 -0.762)
			(size 0.2159 0.2159)
			(layers "F.Cu" "F.Mask" "F.Paste")
			(net "MB0_CM_OV_R")
			(options
				(clearance outline)
				(anchor circle)
			)
			(primitives
				(gr_poly
					(pts
						(arc
							(start -0.3302 -0.4318)
							(mid -0.402042 -0.402042)
							(end -0.4318 -0.3302)
						)
						(arc
							(start -0.4318 0.3302)
							(mid -0.402042 0.402042)
							(end -0.3302 0.4318)
						)
						(arc
							(start 0.3302 0.4318)
							(mid 0.402042 0.402042)
							(end 0.4318 0.3302)
						)
						(arc
							(start 0.4318 -0.3302)
							(mid 0.402042 -0.402042)
							(end 0.3302 -0.4318)
						)
					)
					(width 0)
					(fill yes)
				)
			)
		)
		(pad "2" smd custom
			(at 0 0.762)
			(size 0.2159 0.2159)
			(layers "F.Cu" "F.Mask" "F.Paste")
			(net "AGND_CURRENT_MON")
			(options
				(clearance outline)
				(anchor circle)
			)
			(primitives
				(gr_poly
					(pts
						(arc
							(start -0.3302 -0.4318)
							(mid -0.402042 -0.402042)
							(end -0.4318 -0.3302)
						)
						(arc
							(start -0.4318 0.3302)
							(mid -0.402042 0.402042)
							(end -0.3302 0.4318)
						)
						(arc
							(start 0.3302 0.4318)
							(mid 0.402042 0.402042)
							(end 0.4318 0.3302)
						)
						(arc
							(start 0.4318 -0.3302)
							(mid 0.402042 -0.402042)
							(end 0.3302 -0.4318)
						)
					)
					(width 0)
					(fill yes)
				)
			)
		)
	)
	(footprint ""
		(layer "F.Cu")
		(at 83.994244 -112.65154 90)
		(property "Reference" "R555"
			(at 0 0 90)
			(layer "F.SilkS")
			(hide yes)
			(effects
				(font
					(size 1.27 1.27)
				)
			)
		)
		(property "Value" "10KR2F-2-GP"
			(at 0.064008 -3.993896 90)
			(unlocked yes)
			(layer "F.Fab")
			(hide yes)
			(effects
				(font
					(size 1.016 1.016)
					(thickness 0.1524)
				)
			)
		)
		(property "Device Type" "R402H16"
			(at 0.064008 -5.517896 90)
			(unlocked yes)
			(layer "F.Fab")
			(hide yes)
			(effects
				(font
					(size 1.016 1.016)
					(thickness 0.1524)
				)
			)
		)
		(duplicate_pad_numbers_are_jumpers no)
		(fp_line
			(start 0.508 -0.9398)
			(end -0.508 -0.9398)
			(stroke
				(width 0.1524)
				(type default)
			)
			(layer "F.SilkS")
		)
		(fp_line
			(start -0.508 -0.9398)
			(end -0.508 0.9398)
			(stroke
				(width 0.1524)
				(type default)
			)
			(layer "F.SilkS")
		)
		(fp_rect
			(start -0.508 0.9398)
			(end 0.508 -0.9398)
			(stroke
				(width 0)
				(type default)
			)
			(fill no)
			(layer "F.CrtYd")
		)
		(fp_rect
			(start -0.508 0.9398)
			(end 0.508 -0.9398)
			(stroke
				(width 0)
				(type default)
			)
			(fill no)
			(layer "F.Fab")
		)
		(pad "1" smd custom
			(at 0 -0.4445 90)
			(size 0.1397 0.1397)
			(layers "F.Cu" "F.Mask" "F.Paste")
			(net "P3V3")
			(options
				(clearance outline)
				(anchor circle)
			)
			(primitives
				(gr_poly
					(pts
						(arc
							(start -0.1778 -0.2794)
							(mid -0.249642 -0.249642)
							(end -0.2794 -0.1778)
						)
						(arc
							(start -0.2794 0.1778)
							(mid -0.249642 0.249642)
							(end -0.1778 0.2794)
						)
						(arc
							(start 0.1778 0.2794)
							(mid 0.249642 0.249642)
							(end 0.2794 0.1778)
						)
						(arc
							(start 0.2794 -0.1778)
							(mid 0.249642 -0.249642)
							(end 0.1778 -0.2794)
						)
					)
					(width 0)
					(fill yes)
				)
			)
		)
		(pad "2" smd custom
			(at 0 0.4445 90)
			(size 0.1397 0.1397)
			(layers "F.Cu" "F.Mask" "F.Paste")
			(net "U48_OE")
			(options
				(clearance outline)
				(anchor circle)
			)
			(primitives
				(gr_poly
					(pts
						(arc
							(start -0.1778 -0.2794)
							(mid -0.249642 -0.249642)
							(end -0.2794 -0.1778)
						)
						(arc
							(start -0.2794 0.1778)
							(mid -0.249642 0.249642)
							(end -0.1778 0.2794)
						)
						(arc
							(start 0.1778 0.2794)
							(mid 0.249642 0.249642)
							(end 0.2794 0.1778)
						)
						(arc
							(start 0.2794 -0.1778)
							(mid 0.249642 -0.249642)
							(end 0.1778 -0.2794)
						)
					)
					(width 0)
					(fill yes)
				)
			)
		)
	)
	(footprint ""
		(layer "F.Cu")
		(at 22.83333 -94.850204 180)
		(property "Reference" "C570"
			(at 0 0 180)
			(layer "F.SilkS")
			(hide yes)
			(effects
				(font
					(size 1.27 1.27)
				)
			)
		)
		(property "Value" "SCD1U16V2KX-3GP"
			(at 1.1811 -2.7051 180)
			(unlocked yes)
			(layer "F.Fab")
			(hide yes)
			(effects
				(font
					(size 1.016 1.016)
					(thickness 0.1524)
				)
			)
		)
		(property "Device Type" "C402H22"
			(at 1.1811 -4.2291 180)
			(unlocked yes)
			(layer "F.Fab")
			(hide yes)
			(effects
				(font
					(size 1.016 1.016)
					(thickness 0.1524)
				)
			)
		)
		(duplicate_pad_numbers_are_jumpers no)
		(fp_rect
			(start -0.4318 0.9525)
			(end 0.4318 -0.9525)
			(stroke
				(width 0)
				(type default)
			)
			(fill no)
			(layer "F.CrtYd")
		)
		(fp_rect
			(start -0.4318 0.9525)
			(end 0.4318 -0.9525)
			(stroke
				(width 0)
				(type default)
			)
			(fill no)
			(layer "F.Fab")
		)
		(pad "1" smd custom
			(at 0 -0.4445 180)
			(size 0.1524 0.1524)
			(layers "F.Cu" "F.Mask" "F.Paste")
			(net "VREF1")
			(options
				(clearance outline)
				(anchor circle)
			)
			(primitives
				(gr_poly
					(pts
						(arc
							(start 0.3048 -0.2032)
							(mid 0.275042 -0.275042)
							(end 0.2032 -0.3048)
						)
						(arc
							(start -0.2032 -0.3048)
							(mid -0.275042 -0.275042)
							(end -0.3048 -0.2032)
						)
						(arc
							(start -0.3048 0.2032)
							(mid -0.275042 0.275042)
							(end -0.2032 0.3048)
						)
						(arc
							(start 0.2032 0.3048)
							(mid 0.275042 0.275042)
							(end 0.3048 0.2032)
						)
					)
					(width 0)
					(fill yes)
				)
			)
		)
		(pad "2" smd custom
			(at 0 0.4445 180)
			(size 0.1524 0.1524)
			(layers "F.Cu" "F.Mask" "F.Paste")
			(net "GND")
			(options
				(clearance outline)
				(anchor circle)
			)
			(primitives
				(gr_poly
					(pts
						(arc
							(start 0.3048 -0.2032)
							(mid 0.275042 -0.275042)
							(end 0.2032 -0.3048)
						)
						(arc
							(start -0.2032 -0.3048)
							(mid -0.275042 -0.275042)
							(end -0.3048 -0.2032)
						)
						(arc
							(start -0.3048 0.2032)
							(mid -0.275042 0.275042)
							(end -0.2032 0.3048)
						)
						(arc
							(start 0.2032 0.3048)
							(mid 0.275042 0.275042)
							(end 0.3048 0.2032)
						)
					)
					(width 0)
					(fill yes)
				)
			)
		)
	)
	(footprint ""
		(layer "F.Cu")
		(at 169.6466 -113.0046 180)
		(property "Reference" "R95"
			(at 0 0 180)
			(layer "F.SilkS")
			(hide yes)
			(effects
				(font
					(size 1.27 1.27)
				)
			)
		)
		(property "Value" "0R2J-2-GP"
			(at 0.064008 -3.993896 180)
			(unlocked yes)
			(layer "F.Fab")
			(hide yes)
			(effects
				(font
					(size 1.016 1.016)
					(thickness 0.1524)
				)
			)
		)
		(property "Device Type" "R402H16"
			(at 0.064008 -5.517896 180)
			(unlocked yes)
			(layer "F.Fab")
			(hide yes)
			(effects
				(font
					(size 1.016 1.016)
					(thickness 0.1524)
				)
			)
		)
		(duplicate_pad_numbers_are_jumpers no)
		(fp_line
			(start 0.508 -0.9398)
			(end -0.508 -0.9398)
			(stroke
				(width 0.1524)
				(type default)
			)
			(layer "F.SilkS")
		)
		(fp_line
			(start -0.508 -0.9398)
			(end -0.508 0.9398)
			(stroke
				(width 0.1524)
				(type default)
			)
			(layer "F.SilkS")
		)
		(fp_rect
			(start -0.508 0.9398)
			(end 0.508 -0.9398)
			(stroke
				(width 0)
				(type default)
			)
			(fill no)
			(layer "F.CrtYd")
		)
		(fp_rect
			(start -0.508 0.9398)
			(end 0.508 -0.9398)
			(stroke
				(width 0)
				(type default)
			)
			(fill no)
			(layer "F.Fab")
		)
		(pad "1" smd custom
			(at 0 -0.4445 180)
			(size 0.1397 0.1397)
			(layers "F.Cu" "F.Mask" "F.Paste")
			(net "P5V")
			(options
				(clearance outline)
				(anchor circle)
			)
			(primitives
				(gr_poly
					(pts
						(arc
							(start -0.1778 -0.2794)
							(mid -0.249642 -0.249642)
							(end -0.2794 -0.1778)
						)
						(arc
							(start -0.2794 0.1778)
							(mid -0.249642 0.249642)
							(end -0.1778 0.2794)
						)
						(arc
							(start 0.1778 0.2794)
							(mid 0.249642 0.249642)
							(end 0.2794 0.1778)
						)
						(arc
							(start 0.2794 -0.1778)
							(mid 0.249642 -0.249642)
							(end 0.1778 -0.2794)
						)
					)
					(width 0)
					(fill yes)
				)
			)
		)
		(pad "2" smd custom
			(at 0 0.4445 180)
			(size 0.1397 0.1397)
			(layers "F.Cu" "F.Mask" "F.Paste")
			(net "P1V8_E_BIAS")
			(options
				(clearance outline)
				(anchor circle)
			)
			(primitives
				(gr_poly
					(pts
						(arc
							(start -0.1778 -0.2794)
							(mid -0.249642 -0.249642)
							(end -0.2794 -0.1778)
						)
						(arc
							(start -0.2794 0.1778)
							(mid -0.249642 0.249642)
							(end -0.1778 0.2794)
						)
						(arc
							(start 0.1778 0.2794)
							(mid 0.249642 0.249642)
							(end 0.2794 0.1778)
						)
						(arc
							(start 0.2794 -0.1778)
							(mid 0.249642 -0.249642)
							(end 0.1778 -0.2794)
						)
					)
					(width 0)
					(fill yes)
				)
			)
		)
	)
	(footprint ""
		(layer "F.Cu")
		(at 136.248902 -75.91552 90)
		(property "Reference" "C683"
			(at 0 0 90)
			(layer "F.SilkS")
			(hide yes)
			(effects
				(font
					(size 1.27 1.27)
				)
			)
		)
		(property "Value" "SCD01U16V1KX-GP"
			(at -2.8321 -1.7399 90)
			(unlocked yes)
			(layer "F.Fab")
			(hide yes)
			(effects
				(font
					(size 1.016 1.016)
					(thickness 0.1524)
				)
			)
		)
		(property "Device Type" "C0201H13"
			(at -2.8321 -3.2639 90)
			(unlocked yes)
			(layer "F.Fab")
			(hide yes)
			(effects
				(font
					(size 1.016 1.016)
					(thickness 0.1524)
				)
			)
		)
		(duplicate_pad_numbers_are_jumpers no)
		(fp_rect
			(start -0.2794 0.6477)
			(end 0.2794 -0.6477)
			(stroke
				(width 0)
				(type default)
			)
			(fill no)
			(layer "F.CrtYd")
		)
		(fp_rect
			(start -0.2794 0.6477)
			(end 0.2794 -0.6477)
			(stroke
				(width 0)
				(type default)
			)
			(fill no)
			(layer "F.Fab")
		)
		(pad "1" smd custom
			(at 0 -0.2794 90)
			(size 0.0762 0.0762)
			(layers "F.Cu" "F.Mask" "F.Paste")
			(net "PHY_EXP_TO_CONN_C_8_DN")
			(options
				(clearance outline)
				(anchor circle)
			)
			(primitives
				(gr_poly
					(pts
						(arc
							(start 0.1524 -0.127)
							(mid 0.137521 -0.162921)
							(end 0.1016 -0.1778)
						)
						(arc
							(start -0.1016 -0.1778)
							(mid -0.137521 -0.162921)
							(end -0.1524 -0.127)
						)
						(arc
							(start -0.1524 0.127)
							(mid -0.137521 0.162921)
							(end -0.1016 0.1778)
						)
						(arc
							(start 0.1016 0.1778)
							(mid 0.137521 0.162921)
							(end 0.1524 0.127)
						)
					)
					(width 0)
					(fill yes)
				)
			)
		)
		(pad "2" smd custom
			(at 0 0.2794 90)
			(size 0.0762 0.0762)
			(layers "F.Cu" "F.Mask" "F.Paste")
			(net "PHY_EXP_TO_CONN_8_DN")
			(options
				(clearance outline)
				(anchor circle)
			)
			(primitives
				(gr_poly
					(pts
						(arc
							(start 0.1524 -0.127)
							(mid 0.137521 -0.162921)
							(end 0.1016 -0.1778)
						)
						(arc
							(start -0.1016 -0.1778)
							(mid -0.137521 -0.162921)
							(end -0.1524 -0.127)
						)
						(arc
							(start -0.1524 0.127)
							(mid -0.137521 0.162921)
							(end -0.1016 0.1778)
						)
						(arc
							(start 0.1016 0.1778)
							(mid 0.137521 0.162921)
							(end 0.1524 0.127)
						)
					)
					(width 0)
					(fill yes)
				)
			)
		)
	)
	(footprint ""
		(layer "F.Cu")
		(at 160.274 -86.741 90)
		(property "Reference" "C518"
			(at 0 0 90)
			(layer "F.SilkS")
			(hide yes)
			(effects
				(font
					(size 1.27 1.27)
				)
			)
		)
		(property "Value" "SC1U16V2KX-7-GP"
			(at 1.7526 -1.6002 90)
			(unlocked yes)
			(layer "F.Fab")
			(hide yes)
			(effects
				(font
					(size 1.016 1.016)
					(thickness 0.1524)
				)
			)
		)
		(property "Device Type" "C402-TO0D2H24"
			(at 1.7526 -3.1242 90)
			(unlocked yes)
			(layer "F.Fab")
			(hide yes)
			(effects
				(font
					(size 1.016 1.016)
					(thickness 0.1524)
				)
			)
		)
		(duplicate_pad_numbers_are_jumpers no)
		(fp_rect
			(start -0.4826 0.889)
			(end 0.4826 -0.889)
			(stroke
				(width 0)
				(type default)
			)
			(fill no)
			(layer "F.CrtYd")
		)
		(fp_rect
			(start -0.4826 0.889)
			(end 0.4826 -0.889)
			(stroke
				(width 0)
				(type default)
			)
			(fill no)
			(layer "F.Fab")
		)
		(pad "1" smd custom
			(at 0 -0.4572 90)
			(size 0.1524 0.1524)
			(layers "F.Cu" "F.Mask" "F.Paste")
			(net "P3V3")
			(options
				(clearance outline)
				(anchor circle)
			)
			(primitives
				(gr_poly
					(pts
						(arc
							(start -0.254 0.3048)
							(mid -0.325842 0.275042)
							(end -0.3556 0.2032)
						)
						(arc
							(start -0.3556 -0.2032)
							(mid -0.325842 -0.275042)
							(end -0.254 -0.3048)
						)
						(arc
							(start 0.254 -0.3048)
							(mid 0.325842 -0.275042)
							(end 0.3556 -0.2032)
						)
						(arc
							(start 0.3556 0.2032)
							(mid 0.325842 0.275042)
							(end 0.254 0.3048)
						)
					)
					(width 0)
					(fill yes)
				)
			)
		)
		(pad "2" smd custom
			(at 0 0.4572 90)
			(size 0.1524 0.1524)
			(layers "F.Cu" "F.Mask" "F.Paste")
			(net "GND")
			(options
				(clearance outline)
				(anchor circle)
			)
			(primitives
				(gr_poly
					(pts
						(arc
							(start -0.254 0.3048)
							(mid -0.325842 0.275042)
							(end -0.3556 0.2032)
						)
						(arc
							(start -0.3556 -0.2032)
							(mid -0.325842 -0.275042)
							(end -0.254 -0.3048)
						)
						(arc
							(start 0.254 -0.3048)
							(mid 0.325842 -0.275042)
							(end 0.3556 -0.2032)
						)
						(arc
							(start 0.3556 0.2032)
							(mid 0.325842 0.275042)
							(end 0.254 0.3048)
						)
					)
					(width 0)
					(fill yes)
				)
			)
		)
	)
	(footprint ""
		(layer "F.Cu")
		(at 73.533 -62.23 180)
		(property "Reference" "C262"
			(at 0 0 180)
			(layer "F.SilkS")
			(hide yes)
			(effects
				(font
					(size 1.27 1.27)
				)
			)
		)
		(property "Value" "SC100U6D3V6MX-GP"
			(at -0.0762 -5.1308 180)
			(unlocked yes)
			(layer "F.Fab")
			(hide yes)
			(effects
				(font
					(size 1.016 1.016)
					(thickness 0.1524)
				)
			)
		)
		(property "Device Type" "C1206H71"
			(at -0.127 -6.6548 180)
			(unlocked yes)
			(layer "F.Fab")
			(hide yes)
			(effects
				(font
					(size 1.016 1.016)
					(thickness 0.1524)
				)
			)
		)
		(duplicate_pad_numbers_are_jumpers no)
		(fp_line
			(start 1.016 2.2352)
			(end -1.016 2.2352)
			(stroke
				(width 0.1524)
				(type default)
			)
			(layer "F.SilkS")
		)
		(fp_line
			(start 1.016 0.8382)
			(end 1.016 2.2352)
			(stroke
				(width 0.1524)
				(type default)
			)
			(layer "F.SilkS")
		)
		(fp_line
			(start 1.016 -2.2352)
			(end 1.016 -0.8382)
			(stroke
				(width 0.1524)
				(type default)
			)
			(layer "F.SilkS")
		)
		(fp_line
			(start -1.016 2.2352)
			(end -1.016 0.8382)
			(stroke
				(width 0.1524)
				(type default)
			)
			(layer "F.SilkS")
		)
		(fp_line
			(start -1.016 -0.8382)
			(end -1.016 -2.2352)
			(stroke
				(width 0.1524)
				(type default)
			)
			(layer "F.SilkS")
		)
		(fp_line
			(start -1.016 -2.2352)
			(end 1.016 -2.2352)
			(stroke
				(width 0.1524)
				(type default)
			)
			(layer "F.SilkS")
		)
		(fp_rect
			(start -1.0922 2.3114)
			(end 1.0922 -2.3114)
			(stroke
				(width 0)
				(type default)
			)
			(fill no)
			(layer "F.CrtYd")
		)
		(fp_poly
			(pts
				(xy 1.0922 -2.3114) (xy 1.0922 2.3114) (xy -1.0922 2.3114) (xy -1.0922 -2.3114)
			)
			(stroke
				(width 0)
				(type default)
			)
			(fill no)
			(layer "F.Fab")
		)
		(pad "1" smd rect
			(at 0 -1.397 180)
			(size 1.651 1.27)
			(layers "F.Cu" "F.Mask" "F.Paste")
			(net "GB_VDDA")
		)
		(pad "2" smd rect
			(at 0 1.397 180)
			(size 1.651 1.27)
			(layers "F.Cu" "F.Mask" "F.Paste")
			(net "GND")
		)
	)
	(footprint ""
		(layer "F.Cu")
		(at 171.54652 -115.86464 180)
		(property "Reference" "R607"
			(at 0 0 180)
			(layer "F.SilkS")
			(hide yes)
			(effects
				(font
					(size 1.27 1.27)
				)
			)
		)
		(property "Value" "1KR2J-1-GP"
			(at 0.064008 -3.993896 180)
			(unlocked yes)
			(layer "F.Fab")
			(hide yes)
			(effects
				(font
					(size 1.016 1.016)
					(thickness 0.1524)
				)
			)
		)
		(property "Device Type" "R402H16"
			(at 0.064008 -5.517896 180)
			(unlocked yes)
			(layer "F.Fab")
			(hide yes)
			(effects
				(font
					(size 1.016 1.016)
					(thickness 0.1524)
				)
			)
		)
		(duplicate_pad_numbers_are_jumpers no)
		(fp_line
			(start 0.508 -0.9398)
			(end -0.508 -0.9398)
			(stroke
				(width 0.1524)
				(type default)
			)
			(layer "F.SilkS")
		)
		(fp_line
			(start -0.508 -0.9398)
			(end -0.508 0.9398)
			(stroke
				(width 0.1524)
				(type default)
			)
			(layer "F.SilkS")
		)
		(fp_rect
			(start -0.508 0.9398)
			(end 0.508 -0.9398)
			(stroke
				(width 0)
				(type default)
			)
			(fill no)
			(layer "F.CrtYd")
		)
		(fp_rect
			(start -0.508 0.9398)
			(end 0.508 -0.9398)
			(stroke
				(width 0)
				(type default)
			)
			(fill no)
			(layer "F.Fab")
		)
		(pad "1" smd custom
			(at 0 -0.4445 180)
			(size 0.1397 0.1397)
			(layers "F.Cu" "F.Mask" "F.Paste")
			(net "P1V8_E_PG")
			(options
				(clearance outline)
				(anchor circle)
			)
			(primitives
				(gr_poly
					(pts
						(arc
							(start -0.1778 -0.2794)
							(mid -0.249642 -0.249642)
							(end -0.2794 -0.1778)
						)
						(arc
							(start -0.2794 0.1778)
							(mid -0.249642 0.249642)
							(end -0.1778 0.2794)
						)
						(arc
							(start 0.1778 0.2794)
							(mid 0.249642 0.249642)
							(end 0.2794 0.1778)
						)
						(arc
							(start 0.2794 -0.1778)
							(mid 0.249642 -0.249642)
							(end 0.1778 -0.2794)
						)
					)
					(width 0)
					(fill yes)
				)
			)
		)
		(pad "2" smd custom
			(at 0 0.4445 180)
			(size 0.1397 0.1397)
			(layers "F.Cu" "F.Mask" "F.Paste")
			(net "P3V3")
			(options
				(clearance outline)
				(anchor circle)
			)
			(primitives
				(gr_poly
					(pts
						(arc
							(start -0.1778 -0.2794)
							(mid -0.249642 -0.249642)
							(end -0.2794 -0.1778)
						)
						(arc
							(start -0.2794 0.1778)
							(mid -0.249642 0.249642)
							(end -0.1778 0.2794)
						)
						(arc
							(start 0.1778 0.2794)
							(mid 0.249642 0.249642)
							(end 0.2794 0.1778)
						)
						(arc
							(start 0.2794 -0.1778)
							(mid 0.249642 -0.249642)
							(end 0.1778 -0.2794)
						)
					)
					(width 0)
					(fill yes)
				)
			)
		)
	)
)
